(kicad_pcb
	(version 20260206)
	(generator "pcbnew")
	(generator_version "10.0")
	(general
		(thickness 1.6)
		(legacy_teardrops no)
	)
	(paper "A4")
	(title_block
		(title "03242023_DA0F0TMBIJ0_F0T_Motherboard_J_brd_V01_OCP.brd")
		(comment 1 "Grand Teton / footprints 4852-4858 of 6105")
	)
	(layers
		(0 "F.Cu" signal "TOP")
		(4 "In1.Cu" signal "GND")
		(6 "In2.Cu" signal "IN1")
		(8 "In3.Cu" signal "GND1")
		(10 "In4.Cu" signal "IN2")
		(12 "In5.Cu" signal "GND2")
		(14 "In6.Cu" signal "IN3")
		(16 "In7.Cu" signal "GND3")
		(18 "In8.Cu" signal "VCC")
		(20 "In9.Cu" signal "VCC1")
		(22 "In10.Cu" signal "GND4")
		(24 "In11.Cu" signal "IN4")
		(26 "In12.Cu" signal "GND5")
		(28 "In13.Cu" signal "IN5")
		(30 "In14.Cu" signal "GND6")
		(32 "In15.Cu" signal "IN6")
		(34 "In16.Cu" signal "GND7")
		(2 "B.Cu" signal "BOTTOM")
		(9 "F.Adhes" user "F.Adhesive")
		(11 "B.Adhes" user "B.Adhesive")
		(13 "F.Paste" user "Package Geometry/Pastemask Top")
		(15 "B.Paste" user "Package Geometry/Pastemask Bottom")
		(5 "F.SilkS" user "Ref Des/Silkscreen Top")
		(7 "B.SilkS" user "Ref Des/Silkscreen Bottom")
		(1 "F.Mask" user "Board Geometry/Soldermask Top")
		(3 "B.Mask" user "Board Geometry/Soldermask Bottom")
		(17 "Dwgs.User" user "User.Drawings")
		(19 "Cmts.User" user "User.Comments")
		(21 "Eco1.User" user "User.Eco1")
		(23 "Eco2.User" user "User.Eco2")
		(25 "Edge.Cuts" user "Board Geometry/Outline")
		(27 "Margin" user)
		(31 "F.CrtYd" user "Package Geometry/Place Bound Top")
		(29 "B.CrtYd" user "Package Geometry/Place Bound Bottom")
		(35 "F.Fab" user "Ref Des/Assembly Top")
		(33 "B.Fab" user "Ref Des/Assembly Bottom")
	)
	(footprint ""
		(layer "B.Cu")
		(at 208.152746 -321.554856 -90)
		(property "Reference" "C73"
			(at 0 0 90)
			(layer "B.SilkS")
			(hide yes)
			(effects
				(font
					(size 1.27 1.27)
				)
				(justify mirror)
			)
		)
		(property "Value" ""
			(at 0 0 90)
			(layer "B.Fab")
			(effects
				(font
					(size 1.27 1.27)
				)
				(justify mirror)
			)
		)
		(duplicate_pad_numbers_are_jumpers no)
		(fp_line
			(start -1.524 0.762)
			(end 1.524 0.762)
			(stroke
				(width 0.1524)
				(type default)
			)
			(layer "B.SilkS")
		)
		(fp_line
			(start 1.524 0.762)
			(end 1.524 -0.762)
			(stroke
				(width 0.1524)
				(type default)
			)
			(layer "B.SilkS")
		)
		(fp_line
			(start -1.524 -0.762)
			(end -1.524 0.762)
			(stroke
				(width 0.1524)
				(type default)
			)
			(layer "B.SilkS")
		)
		(fp_line
			(start 1.524 -0.762)
			(end -1.524 -0.762)
			(stroke
				(width 0.1524)
				(type default)
			)
			(layer "B.SilkS")
		)
		(fp_line
			(start -1.1049 0.724916)
			(end -1.1049 -0.724916)
			(stroke
				(width 0.1)
				(type default)
			)
			(layer "B.Fab")
		)
		(fp_line
			(start 1.1049 0.724916)
			(end -1.1049 0.724916)
			(stroke
				(width 0.1)
				(type default)
			)
			(layer "B.Fab")
		)
		(fp_line
			(start -1.1049 -0.724916)
			(end 1.1049 -0.724916)
			(stroke
				(width 0.1)
				(type default)
			)
			(layer "B.Fab")
		)
		(fp_line
			(start 1.1049 -0.724916)
			(end 1.1049 0.724916)
			(stroke
				(width 0.1)
				(type default)
			)
			(layer "B.Fab")
		)
		(pad "1" smd rect
			(at 0.889 0 270)
			(size 1.016 1.27)
			(layers "B.Cu" "B.Mask" "B.Paste")
			(net "P12V_S3_AUX_CPU1_NVDIMM")
		)
		(pad "2" smd rect
			(at -0.889 0 270)
			(size 1.016 1.27)
			(layers "B.Cu" "B.Mask" "B.Paste")
			(net "GND")
		)
	)
	(footprint ""
		(layer "B.Cu")
		(at 196.23278 -316.868048 90)
		(property "Reference" "R3903"
			(at 0 0 90)
			(layer "B.SilkS")
			(hide yes)
			(effects
				(font
					(size 1.27 1.27)
				)
				(justify mirror)
			)
		)
		(property "Value" ""
			(at 0 0 90)
			(layer "B.Fab")
			(effects
				(font
					(size 1.27 1.27)
				)
				(justify mirror)
			)
		)
		(duplicate_pad_numbers_are_jumpers no)
		(fp_line
			(start 0.7874 -0.4064)
			(end -0.7874 -0.4064)
			(stroke
				(width 0.1524)
				(type default)
			)
			(layer "B.SilkS")
		)
		(fp_line
			(start -0.7874 -0.4064)
			(end -0.7874 0.4064)
			(stroke
				(width 0.1524)
				(type default)
			)
			(layer "B.SilkS")
		)
		(fp_line
			(start 0.7874 0.4064)
			(end 0.7874 -0.4064)
			(stroke
				(width 0.1524)
				(type default)
			)
			(layer "B.SilkS")
		)
		(fp_line
			(start -0.7874 0.4064)
			(end 0.7874 0.4064)
			(stroke
				(width 0.1524)
				(type default)
			)
			(layer "B.SilkS")
		)
		(fp_line
			(start 0.67945 -0.305054)
			(end 0.12065 -0.305054)
			(stroke
				(width 0.1)
				(type default)
			)
			(layer "B.Fab")
		)
		(fp_line
			(start 0.12065 -0.305054)
			(end 0.12065 -0.2794)
			(stroke
				(width 0.1)
				(type default)
			)
			(layer "B.Fab")
		)
		(fp_line
			(start -0.12065 -0.3048)
			(end -0.67945 -0.3048)
			(stroke
				(width 0.1)
				(type default)
			)
			(layer "B.Fab")
		)
		(fp_line
			(start -0.67945 -0.3048)
			(end -0.67945 0.3048)
			(stroke
				(width 0.1)
				(type default)
			)
			(layer "B.Fab")
		)
		(fp_line
			(start 0.12065 -0.2794)
			(end -0.12065 -0.2794)
			(stroke
				(width 0.1)
				(type default)
			)
			(layer "B.Fab")
		)
		(fp_line
			(start -0.12065 -0.2794)
			(end -0.12065 -0.3048)
			(stroke
				(width 0.1)
				(type default)
			)
			(layer "B.Fab")
		)
		(fp_line
			(start 0.12065 0.2794)
			(end 0.12065 0.3048)
			(stroke
				(width 0.1)
				(type default)
			)
			(layer "B.Fab")
		)
		(fp_line
			(start -0.120396 0.2794)
			(end 0.12065 0.2794)
			(stroke
				(width 0.1)
				(type default)
			)
			(layer "B.Fab")
		)
		(fp_line
			(start 0.67945 0.3048)
			(end 0.67945 -0.305054)
			(stroke
				(width 0.1)
				(type default)
			)
			(layer "B.Fab")
		)
		(fp_line
			(start 0.12065 0.3048)
			(end 0.67945 0.3048)
			(stroke
				(width 0.1)
				(type default)
			)
			(layer "B.Fab")
		)
		(fp_line
			(start -0.120396 0.3048)
			(end -0.120396 0.2794)
			(stroke
				(width 0.1)
				(type default)
			)
			(layer "B.Fab")
		)
		(fp_line
			(start -0.67945 0.3048)
			(end -0.120396 0.3048)
			(stroke
				(width 0.1)
				(type default)
			)
			(layer "B.Fab")
		)
		(pad "1" smd circle
			(at 0.40005 0 270)
			(size 0 0)
			(layers "B.Cu" "B.Mask" "B.Paste")
			(net "I3C_SPD_DDREFGH_CPU1_LVC1_SCL_4")
		)
		(pad "2" smd circle
			(at -0.40005 0 270)
			(size 0 0)
			(layers "B.Cu" "B.Mask" "B.Paste")
			(net "I3C_SPD_DDREFGH_CPU1_LVC1_SCL")
		)
	)
	(footprint ""
		(layer "B.Cu")
		(at 182.908448 -407.856182 90)
		(property "Reference" "R3909"
			(at 0 0 90)
			(layer "B.SilkS")
			(hide yes)
			(effects
				(font
					(size 1.27 1.27)
				)
				(justify mirror)
			)
		)
		(property "Value" ""
			(at 0 0 90)
			(layer "B.Fab")
			(effects
				(font
					(size 1.27 1.27)
				)
				(justify mirror)
			)
		)
		(duplicate_pad_numbers_are_jumpers no)
		(fp_line
			(start 0.7874 -0.4064)
			(end -0.7874 -0.4064)
			(stroke
				(width 0.1524)
				(type default)
			)
			(layer "B.SilkS")
		)
		(fp_line
			(start -0.7874 -0.4064)
			(end -0.7874 0.4064)
			(stroke
				(width 0.1524)
				(type default)
			)
			(layer "B.SilkS")
		)
		(fp_line
			(start 0.7874 0.4064)
			(end 0.7874 -0.4064)
			(stroke
				(width 0.1524)
				(type default)
			)
			(layer "B.SilkS")
		)
		(fp_line
			(start -0.7874 0.4064)
			(end 0.7874 0.4064)
			(stroke
				(width 0.1524)
				(type default)
			)
			(layer "B.SilkS")
		)
		(fp_line
			(start 0.67945 -0.305054)
			(end 0.12065 -0.305054)
			(stroke
				(width 0.1)
				(type default)
			)
			(layer "B.Fab")
		)
		(fp_line
			(start 0.12065 -0.305054)
			(end 0.12065 -0.2794)
			(stroke
				(width 0.1)
				(type default)
			)
			(layer "B.Fab")
		)
		(fp_line
			(start -0.12065 -0.3048)
			(end -0.67945 -0.3048)
			(stroke
				(width 0.1)
				(type default)
			)
			(layer "B.Fab")
		)
		(fp_line
			(start -0.67945 -0.3048)
			(end -0.67945 0.3048)
			(stroke
				(width 0.1)
				(type default)
			)
			(layer "B.Fab")
		)
		(fp_line
			(start 0.12065 -0.2794)
			(end -0.12065 -0.2794)
			(stroke
				(width 0.1)
				(type default)
			)
			(layer "B.Fab")
		)
		(fp_line
			(start -0.12065 -0.2794)
			(end -0.12065 -0.3048)
			(stroke
				(width 0.1)
				(type default)
			)
			(layer "B.Fab")
		)
		(fp_line
			(start 0.12065 0.2794)
			(end 0.12065 0.3048)
			(stroke
				(width 0.1)
				(type default)
			)
			(layer "B.Fab")
		)
		(fp_line
			(start -0.120396 0.2794)
			(end 0.12065 0.2794)
			(stroke
				(width 0.1)
				(type default)
			)
			(layer "B.Fab")
		)
		(fp_line
			(start 0.67945 0.3048)
			(end 0.67945 -0.305054)
			(stroke
				(width 0.1)
				(type default)
			)
			(layer "B.Fab")
		)
		(fp_line
			(start 0.12065 0.3048)
			(end 0.67945 0.3048)
			(stroke
				(width 0.1)
				(type default)
			)
			(layer "B.Fab")
		)
		(fp_line
			(start -0.120396 0.3048)
			(end -0.120396 0.2794)
			(stroke
				(width 0.1)
				(type default)
			)
			(layer "B.Fab")
		)
		(fp_line
			(start -0.67945 0.3048)
			(end -0.120396 0.3048)
			(stroke
				(width 0.1)
				(type default)
			)
			(layer "B.Fab")
		)
		(pad "1" smd circle
			(at 0.40005 0 270)
			(size 0 0)
			(layers "B.Cu" "B.Mask" "B.Paste")
			(net "SMB_SML1_PMBUS_HSC_SCL")
		)
		(pad "2" smd circle
			(at -0.40005 0 270)
			(size 0 0)
			(layers "B.Cu" "B.Mask" "B.Paste")
			(net "SMB_SML1_PMBUS_HSC_L_SCL")
		)
	)
	(footprint ""
		(layer "B.Cu")
		(at 418.373814 -321.549776 -90)
		(property "Reference" "C27"
			(at 0 0 90)
			(layer "B.SilkS")
			(hide yes)
			(effects
				(font
					(size 1.27 1.27)
				)
				(justify mirror)
			)
		)
		(property "Value" ""
			(at 0 0 90)
			(layer "B.Fab")
			(effects
				(font
					(size 1.27 1.27)
				)
				(justify mirror)
			)
		)
		(duplicate_pad_numbers_are_jumpers no)
		(fp_line
			(start -1.524 0.762)
			(end 1.524 0.762)
			(stroke
				(width 0.1524)
				(type default)
			)
			(layer "B.SilkS")
		)
		(fp_line
			(start 1.524 0.762)
			(end 1.524 -0.762)
			(stroke
				(width 0.1524)
				(type default)
			)
			(layer "B.SilkS")
		)
		(fp_line
			(start -1.524 -0.762)
			(end -1.524 0.762)
			(stroke
				(width 0.1524)
				(type default)
			)
			(layer "B.SilkS")
		)
		(fp_line
			(start 1.524 -0.762)
			(end -1.524 -0.762)
			(stroke
				(width 0.1524)
				(type default)
			)
			(layer "B.SilkS")
		)
		(fp_line
			(start -1.1049 0.724916)
			(end -1.1049 -0.724916)
			(stroke
				(width 0.1)
				(type default)
			)
			(layer "B.Fab")
		)
		(fp_line
			(start 1.1049 0.724916)
			(end -1.1049 0.724916)
			(stroke
				(width 0.1)
				(type default)
			)
			(layer "B.Fab")
		)
		(fp_line
			(start -1.1049 -0.724916)
			(end 1.1049 -0.724916)
			(stroke
				(width 0.1)
				(type default)
			)
			(layer "B.Fab")
		)
		(fp_line
			(start 1.1049 -0.724916)
			(end 1.1049 0.724916)
			(stroke
				(width 0.1)
				(type default)
			)
			(layer "B.Fab")
		)
		(pad "1" smd rect
			(at 0.889 0 270)
			(size 1.016 1.27)
			(layers "B.Cu" "B.Mask" "B.Paste")
			(net "P12V_S3_AUX_CPU0_NVDIMM")
		)
		(pad "2" smd rect
			(at -0.889 0 270)
			(size 1.016 1.27)
			(layers "B.Cu" "B.Mask" "B.Paste")
			(net "GND")
		)
	)
	(footprint ""
		(layer "B.Cu")
		(at 101.404928 -212.049868 180)
		(property "Reference" "C475"
			(at 0 0 0)
			(layer "B.SilkS")
			(hide yes)
			(effects
				(font
					(size 1.27 1.27)
				)
				(justify mirror)
			)
		)
		(property "Value" ""
			(at 0 0 0)
			(layer "B.Fab")
			(effects
				(font
					(size 1.27 1.27)
				)
				(justify mirror)
			)
		)
		(duplicate_pad_numbers_are_jumpers no)
		(fp_line
			(start 1.2954 0.5842)
			(end 1.2954 -0.5842)
			(stroke
				(width 0.1524)
				(type default)
			)
			(layer "B.SilkS")
		)
		(fp_line
			(start 1.2954 -0.5842)
			(end -1.2954 -0.5842)
			(stroke
				(width 0.1524)
				(type default)
			)
			(layer "B.SilkS")
		)
		(fp_line
			(start 0 -0.5842)
			(end 0 0.5842)
			(stroke
				(width 0.1524)
				(type default)
			)
			(layer "B.SilkS")
		)
		(fp_line
			(start -1.2954 0.5842)
			(end 1.2954 0.5842)
			(stroke
				(width 0.1524)
				(type default)
			)
			(layer "B.SilkS")
		)
		(fp_line
			(start -1.2954 -0.5842)
			(end -1.2954 0.5842)
			(stroke
				(width 0.1524)
				(type default)
			)
			(layer "B.SilkS")
		)
		(fp_line
			(start 1.1938 0.4064)
			(end 1.1938 -0.4064)
			(stroke
				(width 0.1)
				(type default)
			)
			(layer "B.Fab")
		)
		(fp_line
			(start 1.1938 -0.4064)
			(end 0.8636 -0.4064)
			(stroke
				(width 0.1)
				(type default)
			)
			(layer "B.Fab")
		)
		(fp_line
			(start 0.8636 0.4572)
			(end 0.8636 0.4064)
			(stroke
				(width 0.1)
				(type default)
			)
			(layer "B.Fab")
		)
		(fp_line
			(start 0.8636 0.4064)
			(end 1.1938 0.4064)
			(stroke
				(width 0.1)
				(type default)
			)
			(layer "B.Fab")
		)
		(fp_line
			(start 0.8636 -0.4064)
			(end 0.8636 -0.4572)
			(stroke
				(width 0.1)
				(type default)
			)
			(layer "B.Fab")
		)
		(fp_line
			(start 0.8636 -0.4572)
			(end -0.8636 -0.4572)
			(stroke
				(width 0.1)
				(type default)
			)
			(layer "B.Fab")
		)
		(fp_line
			(start -0.8636 0.4572)
			(end 0.8636 0.4572)
			(stroke
				(width 0.1)
				(type default)
			)
			(layer "B.Fab")
		)
		(fp_line
			(start -0.8636 0.4064)
			(end -0.8636 0.4572)
			(stroke
				(width 0.1)
				(type default)
			)
			(layer "B.Fab")
		)
		(fp_line
			(start -0.8636 -0.4064)
			(end -1.1938 -0.4064)
			(stroke
				(width 0.1)
				(type default)
			)
			(layer "B.Fab")
		)
		(fp_line
			(start -0.8636 -0.4572)
			(end -0.8636 -0.4064)
			(stroke
				(width 0.1)
				(type default)
			)
			(layer "B.Fab")
		)
		(fp_line
			(start -1.1938 0.4064)
			(end -0.8636 0.4064)
			(stroke
				(width 0.1)
				(type default)
			)
			(layer "B.Fab")
		)
		(fp_line
			(start -1.1938 -0.4064)
			(end -1.1938 0.4064)
			(stroke
				(width 0.1)
				(type default)
			)
			(layer "B.Fab")
		)
		(pad "1" smd rect
			(at 0.7366 0 90)
			(size 0.7112 0.8128)
			(layers "B.Cu" "B.Mask" "B.Paste")
			(net "PVCCFA_EHV_CPU1")
		)
		(pad "2" smd rect
			(at -0.7366 0 90)
			(size 0.7112 0.8128)
			(layers "B.Cu" "B.Mask" "B.Paste")
			(net "GND")
		)
	)
	(footprint ""
		(layer "B.Cu")
		(at 340.521036 -53.908706 180)
		(property "Reference" "R477"
			(at 0 0 0)
			(layer "B.SilkS")
			(hide yes)
			(effects
				(font
					(size 1.27 1.27)
				)
				(justify mirror)
			)
		)
		(property "Value" ""
			(at 0 0 0)
			(layer "B.Fab")
			(effects
				(font
					(size 1.27 1.27)
				)
				(justify mirror)
			)
		)
		(duplicate_pad_numbers_are_jumpers no)
		(fp_line
			(start 0.7874 0.4064)
			(end 0.7874 -0.4064)
			(stroke
				(width 0.1524)
				(type default)
			)
			(layer "B.SilkS")
		)
		(fp_line
			(start 0.7874 -0.4064)
			(end -0.7874 -0.4064)
			(stroke
				(width 0.1524)
				(type default)
			)
			(layer "B.SilkS")
		)
		(fp_line
			(start -0.308864 0.4064)
			(end 0.7874 0.4064)
			(stroke
				(width 0.1524)
				(type default)
			)
			(layer "B.SilkS")
		)
		(fp_line
			(start -0.7874 -0.4064)
			(end -0.7874 0.247142)
			(stroke
				(width 0.1524)
				(type default)
			)
			(layer "B.SilkS")
		)
		(fp_line
			(start 0.67945 0.3048)
			(end 0.67945 -0.305054)
			(stroke
				(width 0.1)
				(type default)
			)
			(layer "B.Fab")
		)
		(fp_line
			(start 0.67945 -0.305054)
			(end 0.12065 -0.305054)
			(stroke
				(width 0.1)
				(type default)
			)
			(layer "B.Fab")
		)
		(fp_line
			(start 0.12065 0.3048)
			(end 0.67945 0.3048)
			(stroke
				(width 0.1)
				(type default)
			)
			(layer "B.Fab")
		)
		(fp_line
			(start 0.12065 0.2794)
			(end 0.12065 0.3048)
			(stroke
				(width 0.1)
				(type default)
			)
			(layer "B.Fab")
		)
		(fp_line
			(start 0.12065 -0.2794)
			(end -0.12065 -0.2794)
			(stroke
				(width 0.1)
				(type default)
			)
			(layer "B.Fab")
		)
		(fp_line
			(start 0.12065 -0.305054)
			(end 0.12065 -0.2794)
			(stroke
				(width 0.1)
				(type default)
			)
			(layer "B.Fab")
		)
		(fp_line
			(start -0.120396 0.3048)
			(end -0.120396 0.2794)
			(stroke
				(width 0.1)
				(type default)
			)
			(layer "B.Fab")
		)
		(fp_line
			(start -0.120396 0.2794)
			(end 0.12065 0.2794)
			(stroke
				(width 0.1)
				(type default)
			)
			(layer "B.Fab")
		)
		(fp_line
			(start -0.12065 -0.2794)
			(end -0.12065 -0.3048)
			(stroke
				(width 0.1)
				(type default)
			)
			(layer "B.Fab")
		)
		(fp_line
			(start -0.12065 -0.3048)
			(end -0.67945 -0.3048)
			(stroke
				(width 0.1)
				(type default)
			)
			(layer "B.Fab")
		)
		(fp_line
			(start -0.67945 0.3048)
			(end -0.120396 0.3048)
			(stroke
				(width 0.1)
				(type default)
			)
			(layer "B.Fab")
		)
		(fp_line
			(start -0.67945 -0.3048)
			(end -0.67945 0.3048)
			(stroke
				(width 0.1)
				(type default)
			)
			(layer "B.Fab")
		)
		(pad "1" smd circle
			(at 0.40005 0)
			(size 0 0)
			(layers "B.Cu" "B.Mask" "B.Paste")
			(net "PD_PCH_XCLK_BIASREF")
		)
		(pad "2" smd circle
			(at -0.40005 0)
			(size 0 0)
			(layers "B.Cu" "B.Mask" "B.Paste")
			(net "GND")
		)
	)
	(footprint ""
		(layer "B.Cu")
		(at 302.218852 -54.389782 180)
		(property "Reference" "C1192"
			(at 0 0 0)
			(layer "B.SilkS")
			(hide yes)
			(effects
				(font
					(size 1.27 1.27)
				)
				(justify mirror)
			)
		)
		(property "Value" ""
			(at 0 0 0)
			(layer "B.Fab")
			(effects
				(font
					(size 1.27 1.27)
				)
				(justify mirror)
			)
		)
		(duplicate_pad_numbers_are_jumpers no)
		(fp_line
			(start 1.2954 0.5842)
			(end 1.2954 -0.5842)
			(stroke
				(width 0.1524)
				(type default)
			)
			(layer "B.SilkS")
		)
		(fp_line
			(start 1.2954 -0.5842)
			(end -1.2954 -0.5842)
			(stroke
				(width 0.1524)
				(type default)
			)
			(layer "B.SilkS")
		)
		(fp_line
			(start 0 -0.5842)
			(end 0 0.5842)
			(stroke
				(width 0.1524)
				(type default)
			)
			(layer "B.SilkS")
		)
		(fp_line
			(start -1.2954 0.5842)
			(end 1.2954 0.5842)
			(stroke
				(width 0.1524)
				(type default)
			)
			(layer "B.SilkS")
		)
		(fp_line
			(start -1.2954 -0.5842)
			(end -1.2954 0.5842)
			(stroke
				(width 0.1524)
				(type default)
			)
			(layer "B.SilkS")
		)
		(fp_line
			(start 1.1938 0.4064)
			(end 1.1938 -0.4064)
			(stroke
				(width 0.1)
				(type default)
			)
			(layer "B.Fab")
		)
		(fp_line
			(start 1.1938 -0.4064)
			(end 0.8636 -0.4064)
			(stroke
				(width 0.1)
				(type default)
			)
			(layer "B.Fab")
		)
		(fp_line
			(start 0.8636 0.4572)
			(end 0.8636 0.4064)
			(stroke
				(width 0.1)
				(type default)
			)
			(layer "B.Fab")
		)
		(fp_line
			(start 0.8636 0.4064)
			(end 1.1938 0.4064)
			(stroke
				(width 0.1)
				(type default)
			)
			(layer "B.Fab")
		)
		(fp_line
			(start 0.8636 -0.4064)
			(end 0.8636 -0.4572)
			(stroke
				(width 0.1)
				(type default)
			)
			(layer "B.Fab")
		)
		(fp_line
			(start 0.8636 -0.4572)
			(end -0.8636 -0.4572)
			(stroke
				(width 0.1)
				(type default)
			)
			(layer "B.Fab")
		)
		(fp_line
			(start -0.8636 0.4572)
			(end 0.8636 0.4572)
			(stroke
				(width 0.1)
				(type default)
			)
			(layer "B.Fab")
		)
		(fp_line
			(start -0.8636 0.4064)
			(end -0.8636 0.4572)
			(stroke
				(width 0.1)
				(type default)
			)
			(layer "B.Fab")
		)
		(fp_line
			(start -0.8636 -0.4064)
			(end -1.1938 -0.4064)
			(stroke
				(width 0.1)
				(type default)
			)
			(layer "B.Fab")
		)
		(fp_line
			(start -0.8636 -0.4572)
			(end -0.8636 -0.4064)
			(stroke
				(width 0.1)
				(type default)
			)
			(layer "B.Fab")
		)
		(fp_line
			(start -1.1938 0.4064)
			(end -0.8636 0.4064)
			(stroke
				(width 0.1)
				(type default)
			)
			(layer "B.Fab")
		)
		(fp_line
			(start -1.1938 -0.4064)
			(end -1.1938 0.4064)
			(stroke
				(width 0.1)
				(type default)
			)
			(layer "B.Fab")
		)
		(pad "1" smd rect
			(at 0.7366 0 90)
			(size 0.7112 0.8128)
			(layers "B.Cu" "B.Mask" "B.Paste")
			(net "P1V05_PCH_AUX")
		)
		(pad "2" smd rect
			(at -0.7366 0 90)
			(size 0.7112 0.8128)
			(layers "B.Cu" "B.Mask" "B.Paste")
			(net "GND")
		)
	)
)
